FILE_TYPE = CONNECTIVITY;
{Allegro Design Entry HDL 17.2-2016 S081 (4005846) 1/11/2022}
"PAGE_NUMBER" = 116;
0"NC";
END.
